# BASEBOARD_FAB2 (Tioga Pass) — schematic netlist excerpt (pin names and nets, part order shuffled) for the footprints in the layout excerpt that follows; sources: Cadence DE-HDL packaged netlist, KiCad conversion of Wiwynn_Tioga_Pass_MB.brd

U7D3  ADM1085  IC  pkg SMT  page 196
  ENIN  = PWRGD_P3V3_STBY
  GND  = GND
  VIN  = VSENSE_P12V_ADM1085
  ENOUT  = PWRGD_DSW_PWROK
  CEXT  = A_ADM1085_CEXT
  VCC  = P3V3_STBY

C1G4  SC1U10V2KX-4-GP  10%  pkg SMD-BCG6  page 224 : \1\ = P5V_STBY ; \2\ = GND
C3M30  CAP_A  1.0UF 6.3V 10% X6S  pkg 0402V  page 127 : A = P1V05_PCH_STBY ; B = GND

(kicad_pcb
	(version 20260206)
	(generator "pcbnew")
	(generator_version "10.0")
	(general
		(thickness 1.6)
		(legacy_teardrops no)
	)
	(paper "A4")
	(title_block
		(title "Wiwynn_Tioga_Pass_MB.brd")
		(comment 1 "Tioga Pass / footprints 4662-4664 of 4770")
	)
	(layers
		(0 "F.Cu" signal "TOP")
		(4 "In1.Cu" signal "L2GND")
		(6 "In2.Cu" signal "L3")
		(8 "In3.Cu" signal "L4GND")
		(10 "In4.Cu" signal "L5")
		(12 "In5.Cu" signal "L6GND")
		(14 "In6.Cu" signal "L7VCC")
		(16 "In7.Cu" signal "L8VCC")
		(18 "In8.Cu" signal "L9GND")
		(20 "In9.Cu" signal "L10")
		(22 "In10.Cu" signal "L11GND")
		(24 "In11.Cu" signal "L12")
		(26 "In12.Cu" signal "L13GND")
		(2 "B.Cu" signal "BOTTOM")
		(9 "F.Adhes" user "F.Adhesive")
		(11 "B.Adhes" user "B.Adhesive")
		(13 "F.Paste" user "Package Geometry/Pastemask Top")
		(15 "B.Paste" user "Package Geometry/Pastemask Bottom")
		(5 "F.SilkS" user "Ref Des/Silkscreen Top")
		(7 "B.SilkS" user "Ref Des/Silkscreen Bottom")
		(1 "F.Mask" user "Board Geometry/Soldermask Top")
		(3 "B.Mask" user "Board Geometry/Soldermask Bottom")
		(17 "Dwgs.User" user "User.Drawings")
		(19 "Cmts.User" user "User.Comments")
		(21 "Eco1.User" user "User.Eco1")
		(23 "Eco2.User" user "User.Eco2")
		(25 "Edge.Cuts" user "Board Geometry/Outline")
		(27 "Margin" user)
		(31 "F.CrtYd" user "Package Geometry/Place Bound Top")
		(29 "B.CrtYd" user "Package Geometry/Place Bound Bottom")
		(35 "F.Fab" user "Ref Des/Assembly Top")
		(33 "B.Fab" user "Ref Des/Assembly Bottom")
	)
	(footprint ""
		(layer "B.Cu")
		(at 5.62356 -6.237986 90)
		(property "Reference" "C1G4"
			(at 0 0 90)
			(layer "B.SilkS")
			(hide yes)
			(effects
				(font
					(size 1.27 1.27)
				)
				(justify mirror)
			)
		)
		(property "Value" "*"
			(at -1.1811 -2.8194 90)
			(unlocked yes)
			(layer "B.Fab")
			(hide yes)
			(effects
				(font
					(size 1.27 1.016)
					(thickness 0.1524)
				)
				(justify mirror)
			)
		)
		(property "Device Type" "SC1U10V2KX-4-GP_SMD-BCG6-SC1U1A"
			(at -1.1811 -4.3434 90)
			(unlocked yes)
			(layer "B.Fab")
			(hide yes)
			(effects
				(font
					(size 1.27 1.016)
					(thickness 0.1524)
				)
				(justify mirror)
			)
		)
		(duplicate_pad_numbers_are_jumpers no)
		(fp_rect
			(start 0.4318 0.9525)
			(end -0.4318 -0.9525)
			(stroke
				(width 0)
				(type default)
			)
			(fill no)
			(layer "B.CrtYd")
		)
		(fp_rect
			(start 0.4318 0.9525)
			(end -0.4318 -0.9525)
			(stroke
				(width 0)
				(type default)
			)
			(fill no)
			(layer "B.Fab")
		)
		(pad "1" smd custom
			(at 0 -0.4445 270)
			(size 0.1524 0.1524)
			(layers "B.Cu" "B.Mask" "B.Paste")
			(net "P5V_STBY")
			(options
				(clearance outline)
				(anchor circle)
			)
			(primitives
				(gr_poly
					(pts
						(arc
							(start 0.3048 0.2032)
							(mid 0.275042 0.275042)
							(end 0.2032 0.3048)
						)
						(arc
							(start -0.2032 0.3048)
							(mid -0.275042 0.275042)
							(end -0.3048 0.2032)
						)
						(arc
							(start -0.3048 -0.2032)
							(mid -0.275042 -0.275042)
							(end -0.2032 -0.3048)
						)
						(arc
							(start 0.2032 -0.3048)
							(mid 0.275042 -0.275042)
							(end 0.3048 -0.2032)
						)
					)
					(width 0)
					(fill yes)
				)
			)
		)
		(pad "2" smd custom
			(at 0 0.4445 270)
			(size 0.1524 0.1524)
			(layers "B.Cu" "B.Mask" "B.Paste")
			(net "GND")
			(options
				(clearance outline)
				(anchor circle)
			)
			(primitives
				(gr_poly
					(pts
						(arc
							(start 0.3048 0.2032)
							(mid 0.275042 0.275042)
							(end 0.2032 0.3048)
						)
						(arc
							(start -0.2032 0.3048)
							(mid -0.275042 0.275042)
							(end -0.3048 0.2032)
						)
						(arc
							(start -0.3048 -0.2032)
							(mid -0.275042 -0.275042)
							(end -0.2032 -0.3048)
						)
						(arc
							(start 0.2032 -0.3048)
							(mid 0.275042 -0.275042)
							(end 0.3048 -0.2032)
						)
					)
					(width 0)
					(fill yes)
				)
			)
		)
	)
	(footprint ""
		(layer "B.Cu")
		(at 376.8598 -131.6228 180)
		(property "Reference" "C3M30"
			(at 0 0 0)
			(layer "B.SilkS")
			(hide yes)
			(effects
				(font
					(size 1.27 1.27)
				)
				(justify mirror)
			)
		)
		(property "Value" ""
			(at 0 0 0)
			(layer "B.Fab")
			(effects
				(font
					(size 1.27 1.27)
				)
				(justify mirror)
			)
		)
		(duplicate_pad_numbers_are_jumpers no)
		(fp_poly
			(pts
				(xy -0.3048 -0.1016) (xy -0.3048 0.9906) (xy 0.3048 0.9906) (xy 0.3048 -0.1016)
			)
			(stroke
				(width 0)
				(type default)
			)
			(fill no)
			(layer "B.CrtYd")
		)
		(fp_line
			(start 0.3048 0.9906)
			(end -0.3048 0.9906)
			(stroke
				(width 0.1)
				(type default)
			)
			(layer "B.Fab")
		)
		(fp_line
			(start 0.3048 -0.1016)
			(end 0.3048 0.9906)
			(stroke
				(width 0.1)
				(type default)
			)
			(layer "B.Fab")
		)
		(fp_line
			(start -0.3048 0.9906)
			(end -0.3048 -0.1016)
			(stroke
				(width 0.1)
				(type default)
			)
			(layer "B.Fab")
		)
		(fp_line
			(start -0.3048 -0.1016)
			(end 0.3048 -0.1016)
			(stroke
				(width 0.1)
				(type default)
			)
			(layer "B.Fab")
		)
		(pad "1" smd rect
			(at 0 0)
			(size 0.508 0.508)
			(layers "B.Cu" "B.Mask" "B.Paste")
			(net "P1V05_PCH_STBY")
		)
		(pad "2" smd rect
			(at 0 0.889)
			(size 0.508 0.508)
			(layers "B.Cu" "B.Mask" "B.Paste")
			(net "GND")
		)
		(zone
			(layer "B.Cu")
			(hatch none 0.5)
			(connect_pads
				(clearance 0)
			)
			(min_thickness 0.25)
			(keepout
				(tracks not_allowed)
				(vias allowed)
				(pads allowed)
				(copperpour not_allowed)
				(footprints allowed)
			)
			(placement
				(enabled no)
				(sheetname "")
			)
			(fill
				(thermal_gap 0.5)
				(thermal_bridge_width 0.5)
				(island_removal_mode 0)
			)
			(polygon
				(pts
					(xy 376.6058 -132.2578) (xy 377.1138 -132.2578) (xy 377.1138 -131.8768) (xy 376.6058 -131.8768)
				)
			)
		)
		(zone
			(layer "B.Cu")
			(hatch none 0.5)
			(connect_pads
				(clearance 0)
			)
			(min_thickness 0.25)
			(keepout
				(tracks allowed)
				(vias not_allowed)
				(pads allowed)
				(copperpour not_allowed)
				(footprints allowed)
			)
			(placement
				(enabled no)
				(sheetname "")
			)
			(fill
				(thermal_gap 0.5)
				(thermal_bridge_width 0.5)
				(island_removal_mode 0)
			)
			(polygon
				(pts
					(xy 376.6058 -131.8768) (xy 377.1138 -131.8768) (xy 377.1138 -132.2578) (xy 376.6058 -132.2578)
				)
			)
		)
	)
	(footprint ""
		(layer "B.Cu")
		(at 419.4175 -6.589014 180)
		(property "Reference" "U7D3"
			(at 1.60147 1.397 270)
			(unlocked yes)
			(layer "B.SilkS")
			(effects
				(font
					(size 0.7874 0.5842)
					(thickness 0.1524)
				)
				(justify mirror)
			)
		)
		(property "Value" ""
			(at 0 0 0)
			(layer "B.Fab")
			(effects
				(font
					(size 1.27 1.27)
				)
				(justify mirror)
			)
		)
		(duplicate_pad_numbers_are_jumpers no)
		(fp_line
			(start -0.760222 1.75006)
			(end -1.146048 1.75006)
			(stroke
				(width 0.1524)
				(type default)
			)
			(layer "B.SilkS")
		)
		(fp_line
			(start -1.146048 -0.450088)
			(end -0.760222 -0.450088)
			(stroke
				(width 0.1524)
				(type default)
			)
			(layer "B.SilkS")
		)
		(fp_circle
			(center 1.194054 -0.610362)
			(end 1.067054 -0.610362)
			(stroke
				(width 0.254)
				(type default)
			)
			(fill no)
			(layer "B.SilkS")
		)
		(fp_poly
			(pts
				(xy -0.277622 -0.450088) (xy -0.277622 1.75006) (xy -1.627378 1.75006) (xy -1.627378 -0.450088)
			)
			(stroke
				(width 0)
				(type default)
			)
			(fill no)
			(layer "B.CrtYd")
		)
		(fp_line
			(start -0.277622 1.75006)
			(end -0.277622 -0.450088)
			(stroke
				(width 0.1)
				(type default)
			)
			(layer "B.Fab")
		)
		(fp_line
			(start -0.277622 -0.450088)
			(end -1.627378 -0.450088)
			(stroke
				(width 0.1)
				(type default)
			)
			(layer "B.Fab")
		)
		(fp_line
			(start -1.627378 1.75006)
			(end -0.277622 1.75006)
			(stroke
				(width 0.1)
				(type default)
			)
			(layer "B.Fab")
		)
		(fp_line
			(start -1.627378 -0.450088)
			(end -1.627378 1.75006)
			(stroke
				(width 0.1)
				(type default)
			)
			(layer "B.Fab")
		)
		(fp_circle
			(center 1.194054 -0.610362)
			(end 1.067054 -0.610362)
			(stroke
				(width 0.254)
				(type default)
			)
			(fill no)
			(layer "B.Fab")
		)
		(pad "1" smd rect
			(at 0 0)
			(size 1.016 0.4064)
			(layers "B.Cu" "B.Mask" "B.Paste")
			(net "PWRGD_P3V3_STBY")
		)
		(pad "2" smd rect
			(at 0 0.649986)
			(size 1.016 0.4064)
			(layers "B.Cu" "B.Mask" "B.Paste")
			(net "GND")
		)
		(pad "3" smd rect
			(at 0 1.299972)
			(size 1.016 0.4064)
			(layers "B.Cu" "B.Mask" "B.Paste")
			(net "VSENSE_P12V_ADM1085")
		)
		(pad "4" smd rect
			(at -1.905 1.299972)
			(size 1.016 0.4064)
			(layers "B.Cu" "B.Mask" "B.Paste")
			(net "PWRGD_DSW_PWROK")
		)
		(pad "5" smd rect
			(at -1.905 0.649986)
			(size 1.016 0.4064)
			(layers "B.Cu" "B.Mask" "B.Paste")
			(net "A_ADM1085_CEXT")
		)
		(pad "6" smd rect
			(at -1.905 0)
			(size 1.016 0.4064)
			(layers "B.Cu" "B.Mask" "B.Paste")
			(net "P3V3_STBY")
		)
	)
)
